# T6G (Grand Teton) — schematic netlist excerpt (pin names and nets, part order shuffled) for the footprints in the layout excerpt that follows; sources: Cadence DE-HDL packaged netlist, KiCad conversion of 04192023_DAF0TMB3IC0_F0TG_MB_C_brd_V02_OCP.brd

J38  SCONN168_ME1016810202011  IO  pkg CON_F168S2H7D_P0-6W2-95_LUH  page 131
  GND_A1  = GND
  GND_A2  = GND
  GND_A3  = GND
  GND_A4  = GND
  GND_A5  = GND
  GND_A6  = GND
  SMCLK  = SMB_OCP_SFF_3V3AUX_BUF_R_SCL
  SMDAT  = SMB_OCP_SFF_3V3AUX_BUF_R_SDA
  \smrst#\  = RST_SMB_OCP_SFF_N
  \prsnta#\  = OCP_SFF_PRSNTA_R_N
  \perst1#\  = RST_PERST1_OCP_SFF_N
  \prsntb2#\  = OCP_SFF_PRSNT2_R_N
  GND_A13  = GND
  REFCLKN1  = CLK_100M_CPU0_CLK03_DN
  REFCLKP1  = CLK_100M_CPU0_CLK03_DP
  GND_A16  = GND
  PERN0  = P5E_CPU0_G3_RX_DN<0>
  PERP0  = P5E_CPU0_G3_RX_DP<0>
  GND_A19  = GND
  PERN1  = P5E_CPU0_G3_RX_DN<1>
  PERP1  = P5E_CPU0_G3_RX_DP<1>
  GND_A22  = GND
  PERN2  = P5E_CPU0_G3_RX_DN<2>
  PERP2  = P5E_CPU0_G3_RX_DP<2>
  GND_A25  = GND
  PERN3  = P5E_CPU0_G3_RX_DN<3>
  PERP3  = P5E_CPU0_G3_RX_DP<3>
  GND_A28  = GND
  GND_A29  = GND
  PERN4  = P5E_CPU0_G3_RX_DN<4>
  PERP4  = P5E_CPU0_G3_RX_DP<4>
  GND_A32  = GND
  PERN5  = P5E_CPU0_G3_RX_DN<5>
  PERP5  = P5E_CPU0_G3_RX_DP<5>
  GND_A35  = GND
  PERN6  = P5E_CPU0_G3_RX_DN<6>
  PERP6  = P5E_CPU0_G3_RX_DP<6>
  GND_A38  = GND
  PERN7  = P5E_CPU0_G3_RX_DN<7>
  PERP7  = P5E_CPU0_G3_RX_DP<7>
  GND_A41  = GND
  \prsntb1#\  = OCP_SFF_PRSNT1_R_N
  GND_A43  = GND
  PERN8  = P5E_CPU0_G3_RX_DN<8>
  PERP8  = P5E_CPU0_G3_RX_DP<8>
  GND_A46  = GND
  PERN9  = P5E_CPU0_G3_RX_DN<9>
  PERP9  = P5E_CPU0_G3_RX_DP<9>
  GND_A49  = GND
  PERN10  = P5E_CPU0_G3_RX_DN<10>
  PERP10  = P5E_CPU0_G3_RX_DP<10>
  GND_A52  = GND
  PERN11  = P5E_CPU0_G3_RX_DN<11>
  PERP11  = P5E_CPU0_G3_RX_DP<11>
  GND_A55  = GND
  PERN12  = P5E_CPU0_G3_RX_DN<12>
  PERP12  = P5E_CPU0_G3_RX_DP<12>
  GND_A58  = GND
  PERN13  = P5E_CPU0_G3_RX_DN<13>
  PERP13  = P5E_CPU0_G3_RX_DP<13>
  GND_A61  = GND
  PERN14  = P5E_CPU0_G3_RX_DN<14>
  PERP14  = P5E_CPU0_G3_RX_DP<14>
  GND_A64  = GND
  PERN15  = P5E_CPU0_G3_RX_DN<15>
  PERP15  = P5E_CPU0_G3_RX_DP<15>
  GND_A67  = GND
  USB_DATN  = USB2_P11_DN
  USB_DATP  = USB2_P11_DP
  \pwrbrk0#\  = OCP_SFF_PWRBRK_N
  \+12v_edge_b1\  = P12V_OCP_SFF_R
  \+12v_edge_b2\  = P12V_OCP_SFF_R
  \+12v_edge_b3\  = P12V_OCP_SFF_R
  \+12v_edge_b4\  = P12V_OCP_SFF_R
  \+12v_edge_b5\  = P12V_OCP_SFF_R
  \+12v_edge_b6\  = P12V_OCP_SFF_R
  \bif0#\  = OCP_SFF_BIF0_R_N
  \bif1#\  = OCP_SFF_BIF1_R_N
  \bif2#\  = OCP_SFF_BIF2_R_N
  \perst0#\  = RST_PERST0_OCP_SFF_N
  \+3.3v_edge\  = P3V3_OCP_SFF
  AUX_PWR_EN  = OCP_SFF_AUX_PWR_EN_R
  GND_B13  = GND
  REFCLKN0  = CLK_100M_CPU0_CLK02_DN
  REFCLKP0  = CLK_100M_CPU0_CLK02_DP
  GND_B16  = GND
  PETN0  = P5E_CPU0_G3_TX_C_DP<0>
  PETP0  = P5E_CPU0_G3_TX_C_DN<0>
  GND_B19  = GND
  PETN1  = P5E_CPU0_G3_TX_C_DP<1>
  PETP1  = P5E_CPU0_G3_TX_C_DN<1>
  GND_B22  = GND
  PETN2  = P5E_CPU0_G3_TX_C_DP<2>
  PETP2  = P5E_CPU0_G3_TX_C_DN<2>
  GND_B25  = GND
  PETN3  = P5E_CPU0_G3_TX_C_DP<3>
  PETP3  = P5E_CPU0_G3_TX_C_DN<3>
  GND_B28  = GND
  GND_B29  = GND
  PETN4  = P5E_CPU0_G3_TX_C_DP<4>
  PETP4  = P5E_CPU0_G3_TX_C_DN<4>
  GND_B32  = GND
  PETN5  = P5E_CPU0_G3_TX_C_DP<5>
  PETP5  = P5E_CPU0_G3_TX_C_DN<5>
  GND_B35  = GND
  PETN6  = P5E_CPU0_G3_TX_C_DP<6>
  PETP6  = P5E_CPU0_G3_TX_C_DN<6>
  GND_B38  = GND
  PETN7  = P5E_CPU0_G3_TX_C_DP<7>
  PETP7  = P5E_CPU0_G3_TX_C_DN<7>
  GND_B41  = GND
  \prsntb0#\  = OCP_SFF_PRSNT0_R_N
  GND_B43  = GND
  PETN8  = P5E_CPU0_G3_TX_C_DP<8>
  PETP8  = P5E_CPU0_G3_TX_C_DN<8>
  GND_B46  = GND
  PETN9  = P5E_CPU0_G3_TX_C_DP<9>
  PETP9  = P5E_CPU0_G3_TX_C_DN<9>
  GND_B49  = GND
  PETN10  = P5E_CPU0_G3_TX_C_DP<10>
  PETP10  = P5E_CPU0_G3_TX_C_DN<10>
  GND_B52  = GND
  PETN11  = P5E_CPU0_G3_TX_C_DP<11>
  PETP11  = P5E_CPU0_G3_TX_C_DN<11>
  GND_B55  = GND
  PETN12  = P5E_CPU0_G3_TX_C_DP<12>
  PETP12  = P5E_CPU0_G3_TX_C_DN<12>
  GND_B58  = GND
  PETN13  = P5E_CPU0_G3_TX_C_DP<13>
  PETP13  = P5E_CPU0_G3_TX_C_DN<13>
  GND_B61  = GND
  PETN14  = P5E_CPU0_G3_TX_C_DP<14>
  PETP14  = P5E_CPU0_G3_TX_C_DN<14>
  GND_B64  = GND
  PETN15  = P5E_CPU0_G3_TX_C_DP<15>
  PETP15  = P5E_CPU0_G3_TX_C_DN<15>
  GND_B67  = GND
  RFU1_NC_B68  = TP_OCP_SFF_B68
  RFU1_NC_B69  = TP_OCP_SFF_B69
  \prsntb3#\  = OCP_SFF_PRSNT3_R_N
  G1  = GND
  G2  = GND
  G3  = GND
  G4  = GND
  G5  = GND
  \perst2#\  = RST_PERST2_OCP_SFF_N
  \perst3#\  = RST_PERST3_OCP_SFF_N
  \wake#\  = IRQ_LVC3_OCP_SFF_WAKE_N
  RBT_ARB_IN  = OCP_SFF_ISO1_RBT_ARB_IN
  RBT_ARB_OUT  = OCP_SFF_ISO2_RBT_ARB_OUT
  SLOT_ID1  = OCP_SFF_ID1
  RBT_TX_EN  = NCSI_OCP_SFF_TX_EN
  RBT_TXD1  = NCSI_OCP_SFF_TXD1
  RBT_TXD0  = NCSI_OCP_SFF_TXD0
  GND_OA10  = GND
  REFCLKN3  = CLK_100M_CPU0_CLK05_DN
  REFCLKP3  = CLK_100M_CPU0_CLK05_DP
  GND_OA13  = GND
  RBT_CLK_IN  = CLK_50M_NCSI_OCP_SFF_ISO
  NIC_PWR_GOOD  = FM_OCP_SFF_PWR_GOOD
  MAIN_PWR_EN  = OCP_SFF_MAIN_PWR_EN_R
  \ld#\  = SGPIO_OCP_SFF_LD_N
  DATA_IN  = SGPIO_OCP_SFF_DATAIN
  DATA_OUT  = SGPIO_OCP_SFF_DATAOUT
  CLK  = SGPIO_OCP_SFF_CLK
  SLOT_ID0  = OCP_SFF_ID0
  RBT_RXD1  = NCSI_OCP_SFF_RXD1
  RBT_RXD0  = NCSI_OCP_SFF_RXD0
  GND_OB10  = GND
  REFCLKN2  = CLK_100M_CPU0_CLK04_DN
  REFCLKP2  = CLK_100M_CPU0_CLK04_DP
  GND_OB13  = GND
  RBT_CRS_DV  = NCSI_OCP_SFF_CRS_DV

(kicad_pcb
	(version 20260206)
	(generator "pcbnew")
	(generator_version "10.0")
	(general
		(thickness 1.6)
		(legacy_teardrops no)
	)
	(paper "A4")
	(title_block
		(title "04192023_DAF0TMB3IC0_F0TG_MB_C_brd_V02_OCP.brd")
		(comment 1 "Grand Teton / footprint 2929 of 8354 (J38), pads 90-133 of 175")
	)
	(layers
		(0 "F.Cu" signal "TOP")
		(4 "In1.Cu" signal "GND")
		(6 "In2.Cu" signal "IN1")
		(8 "In3.Cu" signal "GND1")
		(10 "In4.Cu" signal "IN2")
		(12 "In5.Cu" signal "GND2")
		(14 "In6.Cu" signal "IN3")
		(16 "In7.Cu" signal "GND3")
		(18 "In8.Cu" signal "VCC")
		(20 "In9.Cu" signal "VCC1")
		(22 "In10.Cu" signal "GND4")
		(24 "In11.Cu" signal "IN4")
		(26 "In12.Cu" signal "GND5")
		(28 "In13.Cu" signal "IN5")
		(30 "In14.Cu" signal "GND6")
		(32 "In15.Cu" signal "IN6")
		(34 "In16.Cu" signal "GND7")
		(2 "B.Cu" signal "BOTTOM")
		(9 "F.Adhes" user "F.Adhesive")
		(11 "B.Adhes" user "B.Adhesive")
		(13 "F.Paste" user "Package Geometry/Pastemask Top")
		(15 "B.Paste" user "Package Geometry/Pastemask Bottom")
		(5 "F.SilkS" user "Ref Des/Silkscreen Top")
		(7 "B.SilkS" user "Ref Des/Silkscreen Bottom")
		(1 "F.Mask" user "Board Geometry/Soldermask Top")
		(3 "B.Mask" user "Board Geometry/Soldermask Bottom")
		(17 "Dwgs.User" user "User.Drawings")
		(19 "Cmts.User" user "User.Comments")
		(21 "Eco1.User" user "User.Eco1")
		(23 "Eco2.User" user "User.Eco2")
		(25 "Edge.Cuts" user "Board Geometry/Outline")
		(27 "Margin" user)
		(31 "F.CrtYd" user "Package Geometry/Place Bound Top")
		(29 "B.CrtYd" user "Package Geometry/Place Bound Bottom")
		(35 "F.Fab" user "Ref Des/Assembly Top")
		(33 "B.Fab" user "Ref Des/Assembly Bottom")
	)
	(footprint ""
		(layer "F.Cu")
		(at 421.901874 -5.569966 -90)
		(property "Reference" "J38"
			(at -8.103616 -20.50034 0)
			(unlocked yes)
			(layer "F.SilkS")
			(effects
				(font
					(size 0.7874 0.5842)
					(thickness 0.1524)
				)
				(justify left)
			)
		)
		(property "Value" ""
			(at 0 0 270)
			(layer "F.Fab")
			(effects
				(font
					(size 1.27 1.27)
				)
			)
		)
		(duplicate_pad_numbers_are_jumpers no)
		(pad "B18" smd rect
			(at -5.700014 -8.264906 180)
			(size 0.381 1.4478)
			(layers "F.Cu" "F.Mask" "F.Paste")
			(net "P5E_CPU0_G3_TX_C_DN<0>")
		)
		(pad "B19" smd rect
			(at -5.700014 -7.664958 180)
			(size 0.381 1.4478)
			(layers "F.Cu" "F.Mask" "F.Paste")
			(net "GND")
		)
		(pad "B20" smd rect
			(at -5.700014 -7.06501 180)
			(size 0.381 1.4478)
			(layers "F.Cu" "F.Mask" "F.Paste")
			(net "P5E_CPU0_G3_TX_C_DP<1>")
		)
		(pad "B21" smd rect
			(at -5.700014 -6.465062 180)
			(size 0.381 1.4478)
			(layers "F.Cu" "F.Mask" "F.Paste")
			(net "P5E_CPU0_G3_TX_C_DN<1>")
		)
		(pad "B22" smd rect
			(at -5.700014 -5.865114 180)
			(size 0.381 1.4478)
			(layers "F.Cu" "F.Mask" "F.Paste")
			(net "GND")
		)
		(pad "B23" smd rect
			(at -5.700014 -5.264912 180)
			(size 0.381 1.4478)
			(layers "F.Cu" "F.Mask" "F.Paste")
			(net "P5E_CPU0_G3_TX_C_DP<2>")
		)
		(pad "B24" smd rect
			(at -5.700014 -4.664964 180)
			(size 0.381 1.4478)
			(layers "F.Cu" "F.Mask" "F.Paste")
			(net "P5E_CPU0_G3_TX_C_DN<2>")
		)
		(pad "B25" smd rect
			(at -5.700014 -4.065016 180)
			(size 0.381 1.4478)
			(layers "F.Cu" "F.Mask" "F.Paste")
			(net "GND")
		)
		(pad "B26" smd rect
			(at -5.700014 -3.465068 180)
			(size 0.381 1.4478)
			(layers "F.Cu" "F.Mask" "F.Paste")
			(net "P5E_CPU0_G3_TX_C_DP<3>")
		)
		(pad "B27" smd rect
			(at -5.700014 -2.86512 180)
			(size 0.381 1.4478)
			(layers "F.Cu" "F.Mask" "F.Paste")
			(net "P5E_CPU0_G3_TX_C_DN<3>")
		)
		(pad "B28" smd rect
			(at -5.700014 -2.264918 180)
			(size 0.381 1.4478)
			(layers "F.Cu" "F.Mask" "F.Paste")
			(net "GND")
		)
		(pad "B29" smd rect
			(at -5.700014 1.74498 180)
			(size 0.381 1.4478)
			(layers "F.Cu" "F.Mask" "F.Paste")
			(net "GND")
		)
		(pad "B30" smd rect
			(at -5.700014 2.344928 180)
			(size 0.381 1.4478)
			(layers "F.Cu" "F.Mask" "F.Paste")
			(net "P5E_CPU0_G3_TX_C_DP<4>")
		)
		(pad "B31" smd rect
			(at -5.700014 2.944876 180)
			(size 0.381 1.4478)
			(layers "F.Cu" "F.Mask" "F.Paste")
			(net "P5E_CPU0_G3_TX_C_DN<4>")
		)
		(pad "B32" smd rect
			(at -5.700014 3.545078 180)
			(size 0.381 1.4478)
			(layers "F.Cu" "F.Mask" "F.Paste")
			(net "GND")
		)
		(pad "B33" smd rect
			(at -5.700014 4.145026 180)
			(size 0.381 1.4478)
			(layers "F.Cu" "F.Mask" "F.Paste")
			(net "P5E_CPU0_G3_TX_C_DP<5>")
		)
		(pad "B34" smd rect
			(at -5.700014 4.744974 180)
			(size 0.381 1.4478)
			(layers "F.Cu" "F.Mask" "F.Paste")
			(net "P5E_CPU0_G3_TX_C_DN<5>")
		)
		(pad "B35" smd rect
			(at -5.700014 5.344922 180)
			(size 0.381 1.4478)
			(layers "F.Cu" "F.Mask" "F.Paste")
			(net "GND")
		)
		(pad "B36" smd rect
			(at -5.700014 5.945124 180)
			(size 0.381 1.4478)
			(layers "F.Cu" "F.Mask" "F.Paste")
			(net "P5E_CPU0_G3_TX_C_DP<6>")
		)
		(pad "B37" smd rect
			(at -5.700014 6.545072 180)
			(size 0.381 1.4478)
			(layers "F.Cu" "F.Mask" "F.Paste")
			(net "P5E_CPU0_G3_TX_C_DN<6>")
		)
		(pad "B38" smd rect
			(at -5.700014 7.14502 180)
			(size 0.381 1.4478)
			(layers "F.Cu" "F.Mask" "F.Paste")
			(net "GND")
		)
		(pad "B39" smd rect
			(at -5.700014 7.744968 180)
			(size 0.381 1.4478)
			(layers "F.Cu" "F.Mask" "F.Paste")
			(net "P5E_CPU0_G3_TX_C_DP<7>")
		)
		(pad "B40" smd rect
			(at -5.700014 8.344916 180)
			(size 0.381 1.4478)
			(layers "F.Cu" "F.Mask" "F.Paste")
			(net "P5E_CPU0_G3_TX_C_DN<7>")
		)
		(pad "B41" smd rect
			(at -5.700014 8.945118 180)
			(size 0.381 1.4478)
			(layers "F.Cu" "F.Mask" "F.Paste")
			(net "GND")
		)
		(pad "B42" smd rect
			(at -5.700014 9.545066 180)
			(size 0.381 1.4478)
			(layers "F.Cu" "F.Mask" "F.Paste")
			(net "OCP_SFF_PRSNT0_R_N")
		)
		(pad "B43" smd rect
			(at -5.700014 14.454886 180)
			(size 0.381 1.4478)
			(layers "F.Cu" "F.Mask" "F.Paste")
			(net "GND")
		)
		(pad "B44" smd rect
			(at -5.700014 15.055088 180)
			(size 0.381 1.4478)
			(layers "F.Cu" "F.Mask" "F.Paste")
			(net "P5E_CPU0_G3_TX_C_DP<8>")
		)
		(pad "B45" smd rect
			(at -5.700014 15.655036 180)
			(size 0.381 1.4478)
			(layers "F.Cu" "F.Mask" "F.Paste")
			(net "P5E_CPU0_G3_TX_C_DN<8>")
		)
		(pad "B46" smd rect
			(at -5.700014 16.254984 180)
			(size 0.381 1.4478)
			(layers "F.Cu" "F.Mask" "F.Paste")
			(net "GND")
		)
		(pad "B47" smd rect
			(at -5.700014 16.854932 180)
			(size 0.381 1.4478)
			(layers "F.Cu" "F.Mask" "F.Paste")
			(net "P5E_CPU0_G3_TX_C_DP<9>")
		)
		(pad "B48" smd rect
			(at -5.700014 17.45488 180)
			(size 0.381 1.4478)
			(layers "F.Cu" "F.Mask" "F.Paste")
			(net "P5E_CPU0_G3_TX_C_DN<9>")
		)
		(pad "B49" smd rect
			(at -5.700014 18.055082 180)
			(size 0.381 1.4478)
			(layers "F.Cu" "F.Mask" "F.Paste")
			(net "GND")
		)
		(pad "B50" smd rect
			(at -5.700014 18.65503 180)
			(size 0.381 1.4478)
			(layers "F.Cu" "F.Mask" "F.Paste")
			(net "P5E_CPU0_G3_TX_C_DP<10>")
		)
		(pad "B51" smd rect
			(at -5.700014 19.254978 180)
			(size 0.381 1.4478)
			(layers "F.Cu" "F.Mask" "F.Paste")
			(net "P5E_CPU0_G3_TX_C_DN<10>")
		)
		(pad "B52" smd rect
			(at -5.700014 19.854926 180)
			(size 0.381 1.4478)
			(layers "F.Cu" "F.Mask" "F.Paste")
			(net "GND")
		)
		(pad "B53" smd rect
			(at -5.700014 20.455128 180)
			(size 0.381 1.4478)
			(layers "F.Cu" "F.Mask" "F.Paste")
			(net "P5E_CPU0_G3_TX_C_DP<11>")
		)
		(pad "B54" smd rect
			(at -5.700014 21.055076 180)
			(size 0.381 1.4478)
			(layers "F.Cu" "F.Mask" "F.Paste")
			(net "P5E_CPU0_G3_TX_C_DN<11>")
		)
		(pad "B55" smd rect
			(at -5.700014 21.655024 180)
			(size 0.381 1.4478)
			(layers "F.Cu" "F.Mask" "F.Paste")
			(net "GND")
		)
		(pad "B56" smd rect
			(at -5.700014 22.254972 180)
			(size 0.381 1.4478)
			(layers "F.Cu" "F.Mask" "F.Paste")
			(net "P5E_CPU0_G3_TX_C_DP<12>")
		)
		(pad "B57" smd rect
			(at -5.700014 22.85492 180)
			(size 0.381 1.4478)
			(layers "F.Cu" "F.Mask" "F.Paste")
			(net "P5E_CPU0_G3_TX_C_DN<12>")
		)
		(pad "B58" smd rect
			(at -5.700014 23.455122 180)
			(size 0.381 1.4478)
			(layers "F.Cu" "F.Mask" "F.Paste")
			(net "GND")
		)
		(pad "B59" smd rect
			(at -5.700014 24.05507 180)
			(size 0.381 1.4478)
			(layers "F.Cu" "F.Mask" "F.Paste")
			(net "P5E_CPU0_G3_TX_C_DP<13>")
		)
		(pad "B60" smd rect
			(at -5.700014 24.655018 180)
			(size 0.381 1.4478)
			(layers "F.Cu" "F.Mask" "F.Paste")
			(net "P5E_CPU0_G3_TX_C_DN<13>")
		)
		(pad "B61" smd rect
			(at -5.700014 25.254966 180)
			(size 0.381 1.4478)
			(layers "F.Cu" "F.Mask" "F.Paste")
			(net "GND")
		)
	)
)
